# S9S_MB_2U (Grand Teton) — schematic netlist excerpt (pin names and nets, part order shuffled) for the footprints in the layout excerpt that follows; sources: Cadence DE-HDL packaged netlist, KiCad conversion of 03242023_DA0F0TMBIJ0_F0T_Motherboard_J_brd_V01_OCP.brd

PR1801  Q_RES  3.3 1% CHIP  pkg 0402LF  page 289 : A = SW_PVCCFA_EHV_FIVRA_CPU1_BOOT2 ; B = SW_PVCCFA_EHV_FIVRA_CPU1_BOOT2_

U279  PCA9617ADP  IC  pkg TSSOP8_3XB  page 194
  VCCA  = P3V3_E1S_0
  SCLA  = SMB_E1S_3V3AUX_ISO_SCL_R
  SDAA  = SMB_E1S_3V3AUX_ISO_SDA_R
  GND  = GND
  EN  = SMB_PCIE_E1S_ISO_EN_R
  SDAB  = SMB_SENSOR_E1S_3V3AUX_SDA
  SCLB  = SMB_SENSOR_E1S_3V3AUX_SCL
  VCCB  = P3V3_AUX

(kicad_pcb
	(version 20260206)
	(generator "pcbnew")
	(generator_version "10.0")
	(general
		(thickness 1.6)
		(legacy_teardrops no)
	)
	(paper "A4")
	(title_block
		(title "03242023_DA0F0TMBIJ0_F0T_Motherboard_J_brd_V01_OCP.brd")
		(comment 1 "Grand Teton / footprints 4110-4111 of 6105")
	)
	(layers
		(0 "F.Cu" signal "TOP")
		(4 "In1.Cu" signal "GND")
		(6 "In2.Cu" signal "IN1")
		(8 "In3.Cu" signal "GND1")
		(10 "In4.Cu" signal "IN2")
		(12 "In5.Cu" signal "GND2")
		(14 "In6.Cu" signal "IN3")
		(16 "In7.Cu" signal "GND3")
		(18 "In8.Cu" signal "VCC")
		(20 "In9.Cu" signal "VCC1")
		(22 "In10.Cu" signal "GND4")
		(24 "In11.Cu" signal "IN4")
		(26 "In12.Cu" signal "GND5")
		(28 "In13.Cu" signal "IN5")
		(30 "In14.Cu" signal "GND6")
		(32 "In15.Cu" signal "IN6")
		(34 "In16.Cu" signal "GND7")
		(2 "B.Cu" signal "BOTTOM")
		(9 "F.Adhes" user "F.Adhesive")
		(11 "B.Adhes" user "B.Adhesive")
		(13 "F.Paste" user "Package Geometry/Pastemask Top")
		(15 "B.Paste" user "Package Geometry/Pastemask Bottom")
		(5 "F.SilkS" user "Ref Des/Silkscreen Top")
		(7 "B.SilkS" user "Ref Des/Silkscreen Bottom")
		(1 "F.Mask" user "Board Geometry/Soldermask Top")
		(3 "B.Mask" user "Board Geometry/Soldermask Bottom")
		(17 "Dwgs.User" user "User.Drawings")
		(19 "Cmts.User" user "User.Comments")
		(21 "Eco1.User" user "User.Eco1")
		(23 "Eco2.User" user "User.Eco2")
		(25 "Edge.Cuts" user "Board Geometry/Outline")
		(27 "Margin" user)
		(31 "F.CrtYd" user "Package Geometry/Place Bound Top")
		(29 "B.CrtYd" user "Package Geometry/Place Bound Bottom")
		(35 "F.Fab" user "Ref Des/Assembly Top")
		(33 "B.Fab" user "Ref Des/Assembly Bottom")
	)
	(footprint ""
		(layer "F.Cu")
		(at 216.18575 -43.738292 180)
		(property "Reference" "U279"
			(at -0.69977 -3.434334 0)
			(unlocked yes)
			(layer "F.SilkS")
			(effects
				(font
					(size 0.7874 0.5842)
					(thickness 0.1524)
				)
				(justify left)
			)
		)
		(property "Value" ""
			(at 0 0 180)
			(layer "F.Fab")
			(effects
				(font
					(size 1.27 1.27)
				)
			)
		)
		(duplicate_pad_numbers_are_jumpers no)
		(fp_line
			(start 1.463548 1.549908)
			(end -1.463548 1.549908)
			(stroke
				(width 0.1524)
				(type default)
			)
			(layer "F.SilkS")
		)
		(fp_line
			(start 1.463548 -1.549908)
			(end 1.463548 1.549908)
			(stroke
				(width 0.1524)
				(type default)
			)
			(layer "F.SilkS")
		)
		(fp_line
			(start 0.762 -1.549908)
			(end 1.463548 -1.549908)
			(stroke
				(width 0.1524)
				(type default)
			)
			(layer "F.SilkS")
		)
		(fp_line
			(start 0 -0.762)
			(end 0.762 -1.549908)
			(stroke
				(width 0.1524)
				(type default)
			)
			(layer "F.SilkS")
		)
		(fp_line
			(start -0.787908 -1.549908)
			(end 0 -0.762)
			(stroke
				(width 0.1524)
				(type default)
			)
			(layer "F.SilkS")
		)
		(fp_line
			(start -1.463548 1.549908)
			(end -1.463548 -1.549908)
			(stroke
				(width 0.1524)
				(type default)
			)
			(layer "F.SilkS")
		)
		(fp_line
			(start -1.463548 -1.549908)
			(end -0.787908 -1.549908)
			(stroke
				(width 0.1524)
				(type default)
			)
			(layer "F.SilkS")
		)
		(fp_poly
			(pts
				(xy -2.86004 -1.050036) (xy -3.4798 -0.740156) (xy -3.4798 -1.359916)
			)
			(stroke
				(width 0)
				(type default)
			)
			(fill yes)
			(layer "F.SilkS")
		)
		(fp_line
			(start 1.549908 1.549908)
			(end -1.549908 1.549908)
			(stroke
				(width 0.1)
				(type default)
			)
			(layer "F.Fab")
		)
		(fp_line
			(start 1.549908 -1.549908)
			(end 1.549908 1.549908)
			(stroke
				(width 0.1)
				(type default)
			)
			(layer "F.Fab")
		)
		(fp_line
			(start -1.549908 1.549908)
			(end -1.549908 -1.549908)
			(stroke
				(width 0.1)
				(type default)
			)
			(layer "F.Fab")
		)
		(fp_line
			(start -1.549908 -1.549908)
			(end 1.549908 -1.549908)
			(stroke
				(width 0.1)
				(type default)
			)
			(layer "F.Fab")
		)
		(fp_poly
			(pts
				(xy -3.4798 -1.359916) (xy -2.86004 -1.050036) (xy -3.4798 -0.740156)
			)
			(stroke
				(width 0)
				(type default)
			)
			(fill yes)
			(layer "F.Fab")
		)
		(pad "1" smd rect
			(at -2.175002 -1.050036 270)
			(size 0.6096 1.1684)
			(layers "F.Cu" "F.Mask" "F.Paste")
			(net "P3V3_E1S_0")
		)
		(pad "2" smd rect
			(at -2.175002 -0.32512 270)
			(size 0.4318 1.1684)
			(layers "F.Cu" "F.Mask" "F.Paste")
			(net "SMB_E1S_3V3AUX_ISO_SCL_R")
		)
		(pad "3" smd rect
			(at -2.175002 0.32512 270)
			(size 0.4318 1.1684)
			(layers "F.Cu" "F.Mask" "F.Paste")
			(net "SMB_E1S_3V3AUX_ISO_SDA_R")
		)
		(pad "4" smd rect
			(at -2.175002 1.050036 270)
			(size 0.6096 1.1684)
			(layers "F.Cu" "F.Mask" "F.Paste")
			(net "GND")
		)
		(pad "5" smd rect
			(at 2.175002 1.050036 270)
			(size 0.6096 1.1684)
			(layers "F.Cu" "F.Mask" "F.Paste")
			(net "SMB_PCIE_E1S_ISO_EN_R")
		)
		(pad "6" smd rect
			(at 2.175002 0.32512 270)
			(size 0.4318 1.1684)
			(layers "F.Cu" "F.Mask" "F.Paste")
			(net "SMB_SENSOR_E1S_3V3AUX_SDA")
		)
		(pad "7" smd rect
			(at 2.175002 -0.32512 270)
			(size 0.4318 1.1684)
			(layers "F.Cu" "F.Mask" "F.Paste")
			(net "SMB_SENSOR_E1S_3V3AUX_SCL")
		)
		(pad "8" smd rect
			(at 2.175002 -1.050036 270)
			(size 0.6096 1.1684)
			(layers "F.Cu" "F.Mask" "F.Paste")
			(net "P3V3_AUX")
		)
	)
	(footprint ""
		(layer "F.Cu")
		(at 51.860196 -358.20223 90)
		(property "Reference" "PR1801"
			(at 0 0 90)
			(layer "F.SilkS")
			(hide yes)
			(effects
				(font
					(size 1.27 1.27)
				)
			)
		)
		(property "Value" ""
			(at 0 0 90)
			(layer "F.Fab")
			(effects
				(font
					(size 1.27 1.27)
				)
			)
		)
		(duplicate_pad_numbers_are_jumpers no)
		(fp_line
			(start 0.7874 -0.4064)
			(end 0.7874 0.4064)
			(stroke
				(width 0.1524)
				(type default)
			)
			(layer "F.SilkS")
		)
		(fp_line
			(start -0.7874 -0.4064)
			(end 0.7874 -0.4064)
			(stroke
				(width 0.1524)
				(type default)
			)
			(layer "F.SilkS")
		)
		(fp_line
			(start 0.7874 0.4064)
			(end -0.7874 0.4064)
			(stroke
				(width 0.1524)
				(type default)
			)
			(layer "F.SilkS")
		)
		(fp_line
			(start -0.7874 0.4064)
			(end -0.7874 -0.4064)
			(stroke
				(width 0.1524)
				(type default)
			)
			(layer "F.SilkS")
		)
		(fp_line
			(start -0.12065 -0.305054)
			(end -0.12065 -0.2794)
			(stroke
				(width 0.1)
				(type default)
			)
			(layer "F.Fab")
		)
		(fp_line
			(start -0.67945 -0.305054)
			(end -0.12065 -0.305054)
			(stroke
				(width 0.1)
				(type default)
			)
			(layer "F.Fab")
		)
		(fp_line
			(start 0.67945 -0.3048)
			(end 0.67945 0.3048)
			(stroke
				(width 0.1)
				(type default)
			)
			(layer "F.Fab")
		)
		(fp_line
			(start 0.12065 -0.3048)
			(end 0.67945 -0.3048)
			(stroke
				(width 0.1)
				(type default)
			)
			(layer "F.Fab")
		)
		(fp_line
			(start 0.12065 -0.2794)
			(end 0.12065 -0.3048)
			(stroke
				(width 0.1)
				(type default)
			)
			(layer "F.Fab")
		)
		(fp_line
			(start -0.12065 -0.2794)
			(end 0.12065 -0.2794)
			(stroke
				(width 0.1)
				(type default)
			)
			(layer "F.Fab")
		)
		(fp_line
			(start 0.120396 0.2794)
			(end -0.12065 0.2794)
			(stroke
				(width 0.1)
				(type default)
			)
			(layer "F.Fab")
		)
		(fp_line
			(start -0.12065 0.2794)
			(end -0.12065 0.3048)
			(stroke
				(width 0.1)
				(type default)
			)
			(layer "F.Fab")
		)
		(fp_line
			(start 0.67945 0.3048)
			(end 0.120396 0.3048)
			(stroke
				(width 0.1)
				(type default)
			)
			(layer "F.Fab")
		)
		(fp_line
			(start 0.120396 0.3048)
			(end 0.120396 0.2794)
			(stroke
				(width 0.1)
				(type default)
			)
			(layer "F.Fab")
		)
		(fp_line
			(start -0.12065 0.3048)
			(end -0.67945 0.3048)
			(stroke
				(width 0.1)
				(type default)
			)
			(layer "F.Fab")
		)
		(fp_line
			(start -0.67945 0.3048)
			(end -0.67945 -0.305054)
			(stroke
				(width 0.1)
				(type default)
			)
			(layer "F.Fab")
		)
		(pad "1" smd circle
			(at -0.40005 0 90)
			(size 0 0)
			(layers "F.Cu" "F.Mask" "F.Paste")
			(net "SW_PVCCFA_EHV_FIVRA_CPU1_BOOT2")
		)
		(pad "2" smd circle
			(at 0.40005 0 90)
			(size 0 0)
			(layers "F.Cu" "F.Mask" "F.Paste")
			(net "SW_PVCCFA_EHV_FIVRA_CPU1_BOOT2_")
		)
	)
)
